(kicad_pcb
	(version 20260206)
	(generator "pcbnew")
	(generator_version "10.0")
	(general
		(thickness 1.6)
		(legacy_teardrops no)
	)
	(paper "A4")
	(title_block
		(title "04192023_DAF0TMB3IC0_F0TG_MB_C_brd_V02_OCP.brd")
		(comment 1 "Grand Teton / footprint 3955 of 8354 (U25), pads 3113-3224 of 6102")
	)
	(layers
		(0 "F.Cu" signal "TOP")
		(4 "In1.Cu" signal "GND")
		(6 "In2.Cu" signal "IN1")
		(8 "In3.Cu" signal "GND1")
		(10 "In4.Cu" signal "IN2")
		(12 "In5.Cu" signal "GND2")
		(14 "In6.Cu" signal "IN3")
		(16 "In7.Cu" signal "GND3")
		(18 "In8.Cu" signal "VCC")
		(20 "In9.Cu" signal "VCC1")
		(22 "In10.Cu" signal "GND4")
		(24 "In11.Cu" signal "IN4")
		(26 "In12.Cu" signal "GND5")
		(28 "In13.Cu" signal "IN5")
		(30 "In14.Cu" signal "GND6")
		(32 "In15.Cu" signal "IN6")
		(34 "In16.Cu" signal "GND7")
		(2 "B.Cu" signal "BOTTOM")
		(9 "F.Adhes" user "F.Adhesive")
		(11 "B.Adhes" user "B.Adhesive")
		(13 "F.Paste" user "Package Geometry/Pastemask Top")
		(15 "B.Paste" user "Package Geometry/Pastemask Bottom")
		(5 "F.SilkS" user "Ref Des/Silkscreen Top")
		(7 "B.SilkS" user "Ref Des/Silkscreen Bottom")
		(1 "F.Mask" user "Board Geometry/Soldermask Top")
		(3 "B.Mask" user "Board Geometry/Soldermask Bottom")
		(17 "Dwgs.User" user "User.Drawings")
		(19 "Cmts.User" user "User.Comments")
		(21 "Eco1.User" user "User.Eco1")
		(23 "Eco2.User" user "User.Eco2")
		(25 "Edge.Cuts" user "Board Geometry/Outline")
		(27 "Margin" user)
		(31 "F.CrtYd" user "Package Geometry/Place Bound Top")
		(29 "B.CrtYd" user "Package Geometry/Place Bound Bottom")
		(35 "F.Fab" user "Ref Des/Assembly Top")
		(33 "B.Fab" user "Ref Des/Assembly Bottom")
	)
	(footprint ""
		(layer "F.Cu")
		(at 359.867962 -258.880102 180)
		(property "Reference" "U25"
			(at -45.78477 -62.086744 0)
			(unlocked yes)
			(layer "F.SilkS")
			(effects
				(font
					(size 0.7874 0.5842)
					(thickness 0.1524)
				)
			)
		)
		(property "Value" ""
			(at 0 0 180)
			(layer "F.Fab")
			(effects
				(font
					(size 1.27 1.27)
				)
			)
		)
		(duplicate_pad_numbers_are_jumpers no)
		(pad "CE17" smd circle
			(at -19.420078 17.370044 180)
			(size 0.450088 0.450088)
			(layers "F.Cu" "F.Mask" "F.Paste")
			(net "M_J_CPU0_SB_DQS_DN<5>")
		)
		(pad "CE18" smd circle
			(at -18.480024 17.370044 180)
			(size 0.450088 0.450088)
			(layers "F.Cu" "F.Mask" "F.Paste")
			(net "GND")
		)
		(pad "CE19" smd circle
			(at -17.53997 17.370044 180)
			(size 0.450088 0.450088)
			(layers "F.Cu" "F.Mask" "F.Paste")
			(net "M_I_CPU0_SB_DQS_DN<0>")
		)
		(pad "CE20" smd circle
			(at -16.599916 17.370044 180)
			(size 0.450088 0.450088)
			(layers "F.Cu" "F.Mask" "F.Paste")
			(net "GND")
		)
		(pad "CE21" smd circle
			(at -15.660116 17.370044 180)
			(size 0.450088 0.450088)
			(layers "F.Cu" "F.Mask" "F.Paste")
			(net "M_I_CPU0_SB_DQS_DN<5>")
		)
		(pad "CE22" smd circle
			(at -14.720062 17.370044 180)
			(size 0.450088 0.450088)
			(layers "F.Cu" "F.Mask" "F.Paste")
			(net "GND")
		)
		(pad "CE23" smd circle
			(at -13.780008 17.370044 180)
			(size 0.450088 0.450088)
			(layers "F.Cu" "F.Mask" "F.Paste")
			(net "P5E_CPU0_P3_TX_DN<15>")
		)
		(pad "CE24" smd circle
			(at -12.839954 17.370044 180)
			(size 0.450088 0.450088)
			(layers "F.Cu" "F.Mask" "F.Paste")
			(net "P5E_CPU0_P3_TX_DP<15>")
		)
		(pad "CE25" smd circle
			(at -11.8999 17.370044 180)
			(size 0.450088 0.450088)
			(layers "F.Cu" "F.Mask" "F.Paste")
			(net "GND")
		)
		(pad "CE26" smd circle
			(at -10.9601 17.370044 180)
			(size 0.450088 0.450088)
			(layers "F.Cu" "F.Mask" "F.Paste")
			(net "P5E_CPU0_P3_TX_DN<12>")
		)
		(pad "CE27" smd circle
			(at -10.020046 17.370044 180)
			(size 0.450088 0.450088)
			(layers "F.Cu" "F.Mask" "F.Paste")
			(net "P5E_CPU0_P3_TX_DP<12>")
		)
		(pad "CE28" smd circle
			(at -9.079992 17.370044 180)
			(size 0.450088 0.450088)
			(layers "F.Cu" "F.Mask" "F.Paste")
			(net "GND")
		)
		(pad "CE29" smd circle
			(at -8.139938 17.370044 180)
			(size 0.450088 0.450088)
			(layers "F.Cu" "F.Mask" "F.Paste")
			(net "P5E_CPU0_P3_TX_DN<9>")
		)
		(pad "CE30" smd circle
			(at -7.199884 17.370044 180)
			(size 0.450088 0.450088)
			(layers "F.Cu" "F.Mask" "F.Paste")
			(net "P5E_CPU0_P3_TX_DP<9>")
		)
		(pad "CE31" smd circle
			(at -6.260084 17.370044 180)
			(size 0.450088 0.450088)
			(layers "F.Cu" "F.Mask" "F.Paste")
			(net "GND")
		)
		(pad "CE32" smd circle
			(at -5.32003 17.370044 180)
			(size 0.450088 0.450088)
			(layers "F.Cu" "F.Mask" "F.Paste")
			(net "P5E_CPU0_P3_TX_DN<6>")
		)
		(pad "CE33" smd circle
			(at -4.379976 17.370044 180)
			(size 0.450088 0.450088)
			(layers "F.Cu" "F.Mask" "F.Paste")
			(net "P5E_CPU0_P3_TX_DP<6>")
		)
		(pad "CE34" smd circle
			(at -3.439922 17.370044 180)
			(size 0.450088 0.450088)
			(layers "F.Cu" "F.Mask" "F.Paste")
			(net "GND")
		)
		(pad "CE35" smd circle
			(at -2.500122 17.370044 180)
			(size 0.450088 0.450088)
			(layers "F.Cu" "F.Mask" "F.Paste")
			(net "GND")
		)
		(pad "CE36" smd circle
			(at -1.560068 17.370044 180)
			(size 0.450088 0.450088)
			(layers "F.Cu" "F.Mask" "F.Paste")
			(net "GND")
		)
		(pad "CE40" smd circle
			(at 1.260094 17.370044 180)
			(size 0.450088 0.450088)
			(layers "F.Cu" "F.Mask" "F.Paste")
			(net "GND")
		)
		(pad "CE41" smd circle
			(at 2.199894 17.370044 180)
			(size 0.450088 0.450088)
			(layers "F.Cu" "F.Mask" "F.Paste")
			(net "GND")
		)
		(pad "CE42" smd circle
			(at 3.139948 17.370044 180)
			(size 0.450088 0.450088)
			(layers "F.Cu" "F.Mask" "F.Paste")
			(net "GND")
		)
		(pad "CE43" smd circle
			(at 4.080002 17.370044 180)
			(size 0.450088 0.450088)
			(layers "F.Cu" "F.Mask" "F.Paste")
			(net "P5E_CPU0_P1_RX_DP<9>")
		)
		(pad "CE44" smd circle
			(at 5.020056 17.370044 180)
			(size 0.450088 0.450088)
			(layers "F.Cu" "F.Mask" "F.Paste")
			(net "P5E_CPU0_P1_RX_DN<9>")
		)
		(pad "CE45" smd circle
			(at 5.96011 17.370044 180)
			(size 0.450088 0.450088)
			(layers "F.Cu" "F.Mask" "F.Paste")
			(net "GND")
		)
		(pad "CE46" smd circle
			(at 6.89991 17.370044 180)
			(size 0.450088 0.450088)
			(layers "F.Cu" "F.Mask" "F.Paste")
			(net "P5E_CPU0_P1_RX_DP<6>")
		)
		(pad "CE47" smd circle
			(at 7.839964 17.370044 180)
			(size 0.450088 0.450088)
			(layers "F.Cu" "F.Mask" "F.Paste")
			(net "P5E_CPU0_P1_RX_DN<6>")
		)
		(pad "CE48" smd circle
			(at 8.780018 17.370044 180)
			(size 0.450088 0.450088)
			(layers "F.Cu" "F.Mask" "F.Paste")
			(net "GND")
		)
		(pad "CE49" smd circle
			(at 9.720072 17.370044 180)
			(size 0.450088 0.450088)
			(layers "F.Cu" "F.Mask" "F.Paste")
			(net "P5E_CPU0_P1_RX_DP<3>")
		)
		(pad "CE50" smd circle
			(at 10.659872 17.370044 180)
			(size 0.450088 0.450088)
			(layers "F.Cu" "F.Mask" "F.Paste")
			(net "P5E_CPU0_P1_RX_DN<3>")
		)
		(pad "CE51" smd circle
			(at 11.599926 17.370044 180)
			(size 0.450088 0.450088)
			(layers "F.Cu" "F.Mask" "F.Paste")
			(net "GND")
		)
		(pad "CE52" smd circle
			(at 12.53998 17.370044 180)
			(size 0.450088 0.450088)
			(layers "F.Cu" "F.Mask" "F.Paste")
			(net "P5E_CPU0_P1_RX_DP<0>")
		)
		(pad "CE53" smd circle
			(at 13.480034 17.370044 180)
			(size 0.450088 0.450088)
			(layers "F.Cu" "F.Mask" "F.Paste")
			(net "P5E_CPU0_P1_RX_DN<0>")
		)
		(pad "CE54" smd circle
			(at 14.420088 17.370044 180)
			(size 0.450088 0.450088)
			(layers "F.Cu" "F.Mask" "F.Paste")
			(net "GND")
		)
		(pad "CE55" smd circle
			(at 15.359888 17.370044 180)
			(size 0.450088 0.450088)
			(layers "F.Cu" "F.Mask" "F.Paste")
			(net "M_C_CPU0_SB_DQS_DN<5>")
		)
		(pad "CE56" smd circle
			(at 16.299942 17.370044 180)
			(size 0.450088 0.450088)
			(layers "F.Cu" "F.Mask" "F.Paste")
			(net "GND")
		)
		(pad "CE57" smd circle
			(at 17.239996 17.370044 180)
			(size 0.450088 0.450088)
			(layers "F.Cu" "F.Mask" "F.Paste")
			(net "M_C_CPU0_SB_DQS_DN<0>")
		)
		(pad "CE58" smd circle
			(at 18.18005 17.370044 180)
			(size 0.450088 0.450088)
			(layers "F.Cu" "F.Mask" "F.Paste")
			(net "GND")
		)
		(pad "CE59" smd circle
			(at 19.120104 17.370044 180)
			(size 0.450088 0.450088)
			(layers "F.Cu" "F.Mask" "F.Paste")
			(net "M_D_CPU0_SB_DQS_DN<5>")
		)
		(pad "CE60" smd circle
			(at 20.059904 17.370044 180)
			(size 0.450088 0.450088)
			(layers "F.Cu" "F.Mask" "F.Paste")
			(net "M_D_CPU0_SB_DQS_DN<0>")
		)
		(pad "CE61" smd circle
			(at 20.999958 17.370044 180)
			(size 0.450088 0.450088)
			(layers "F.Cu" "F.Mask" "F.Paste")
			(net "GND")
		)
		(pad "CE62" smd circle
			(at 21.940012 17.370044 180)
			(size 0.450088 0.450088)
			(layers "F.Cu" "F.Mask" "F.Paste")
			(net "M_B_CPU0_SB_DQS_DN<5>")
		)
		(pad "CE63" smd circle
			(at 22.880066 17.370044 180)
			(size 0.450088 0.450088)
			(layers "F.Cu" "F.Mask" "F.Paste")
			(net "GND")
		)
		(pad "CE64" smd circle
			(at 23.82012 17.370044 180)
			(size 0.450088 0.450088)
			(layers "F.Cu" "F.Mask" "F.Paste")
			(net "M_B_CPU0_SB_DQS_DN<0>")
		)
		(pad "CE65" smd circle
			(at 24.75992 17.370044 180)
			(size 0.450088 0.450088)
			(layers "F.Cu" "F.Mask" "F.Paste")
			(net "GND")
		)
		(pad "CE66" smd circle
			(at 25.699974 17.370044 180)
			(size 0.450088 0.450088)
			(layers "F.Cu" "F.Mask" "F.Paste")
			(net "M_F_CPU0_SB_DQS_DN<5>")
		)
		(pad "CE67" smd circle
			(at 26.640028 17.370044 180)
			(size 0.450088 0.450088)
			(layers "F.Cu" "F.Mask" "F.Paste")
			(net "M_F_CPU0_SB_DQS_DN<0>")
		)
		(pad "CE68" smd circle
			(at 27.580082 17.370044 180)
			(size 0.450088 0.450088)
			(layers "F.Cu" "F.Mask" "F.Paste")
			(net "GND")
		)
		(pad "CE69" smd circle
			(at 28.519882 17.370044 180)
			(size 0.450088 0.450088)
			(layers "F.Cu" "F.Mask" "F.Paste")
			(net "M_E_CPU0_SB_DQS_DN<5>")
		)
		(pad "CE70" smd circle
			(at 29.459936 17.370044 180)
			(size 0.450088 0.450088)
			(layers "F.Cu" "F.Mask" "F.Paste")
			(net "GND")
		)
		(pad "CE71" smd circle
			(at 30.39999 17.370044 180)
			(size 0.450088 0.450088)
			(layers "F.Cu" "F.Mask" "F.Paste")
			(net "M_E_CPU0_SB_DQS_DN<0>")
		)
		(pad "CE72" smd circle
			(at 31.340044 17.370044 180)
			(size 0.450088 0.450088)
			(layers "F.Cu" "F.Mask" "F.Paste")
			(net "GND")
		)
		(pad "CE73" smd circle
			(at 32.280098 17.370044 180)
			(size 0.450088 0.450088)
			(layers "F.Cu" "F.Mask" "F.Paste")
			(net "M_A_CPU0_SB_DQS_DN<5>")
		)
		(pad "CE74" smd circle
			(at 33.219898 17.370044 180)
			(size 0.450088 0.450088)
			(layers "F.Cu" "F.Mask" "F.Paste")
			(net "M_A_CPU0_SB_DQS_DN<0>")
		)
		(pad "CE75" smd circle
			(at 34.159952 17.370044 180)
			(size 0.450088 0.450088)
			(layers "F.Cu" "F.Mask" "F.Paste")
			(net "GND")
		)
		(pad "CF2" smd circle
			(at -33.990026 18.18005 180)
			(size 0.450088 0.450088)
			(layers "F.Cu" "F.Mask" "F.Paste")
			(net "M_G_CPU0_SB_DQ<4>")
		)
		(pad "CF3" smd circle
			(at -33.049972 18.18005 180)
			(size 0.450088 0.450088)
			(layers "F.Cu" "F.Mask" "F.Paste")
			(net "GND")
		)
		(pad "CF4" smd circle
			(at -32.109918 18.18005 180)
			(size 0.450088 0.450088)
			(layers "F.Cu" "F.Mask" "F.Paste")
			(net "M_G_CPU0_SB_DQS_DP<5>")
		)
		(pad "CF5" smd circle
			(at -31.170118 18.18005 180)
			(size 0.450088 0.450088)
			(layers "F.Cu" "F.Mask" "F.Paste")
			(net "GND")
		)
		(pad "CF6" smd circle
			(at -30.230064 18.18005 180)
			(size 0.450088 0.450088)
			(layers "F.Cu" "F.Mask" "F.Paste")
			(net "M_K_CPU0_SB_DQ<4>")
		)
		(pad "CF7" smd circle
			(at -29.29001 18.18005 180)
			(size 0.450088 0.450088)
			(layers "F.Cu" "F.Mask" "F.Paste")
			(net "M_K_CPU0_SB_DQS_DP<5>")
		)
		(pad "CF8" smd circle
			(at -28.349956 18.18005 180)
			(size 0.450088 0.450088)
			(layers "F.Cu" "F.Mask" "F.Paste")
			(net "GND")
		)
		(pad "CF9" smd circle
			(at -27.409902 18.18005 180)
			(size 0.450088 0.450088)
			(layers "F.Cu" "F.Mask" "F.Paste")
			(net "M_L_CPU0_SB_DQ<4>")
		)
		(pad "CF10" smd circle
			(at -26.470102 18.18005 180)
			(size 0.450088 0.450088)
			(layers "F.Cu" "F.Mask" "F.Paste")
			(net "GND")
		)
		(pad "CF11" smd circle
			(at -25.530048 18.18005 180)
			(size 0.450088 0.450088)
			(layers "F.Cu" "F.Mask" "F.Paste")
			(net "M_L_CPU0_SB_DQS_DP<5>")
		)
		(pad "CF12" smd circle
			(at -24.589994 18.18005 180)
			(size 0.450088 0.450088)
			(layers "F.Cu" "F.Mask" "F.Paste")
			(net "GND")
		)
		(pad "CF13" smd circle
			(at -23.64994 18.18005 180)
			(size 0.450088 0.450088)
			(layers "F.Cu" "F.Mask" "F.Paste")
			(net "M_H_CPU0_SB_DQ<4>")
		)
		(pad "CF14" smd circle
			(at -22.709886 18.18005 180)
			(size 0.450088 0.450088)
			(layers "F.Cu" "F.Mask" "F.Paste")
			(net "M_H_CPU0_SB_DQS_DP<5>")
		)
		(pad "CF15" smd circle
			(at -21.770086 18.18005 180)
			(size 0.450088 0.450088)
			(layers "F.Cu" "F.Mask" "F.Paste")
			(net "GND")
		)
		(pad "CF16" smd circle
			(at -20.830032 18.18005 180)
			(size 0.450088 0.450088)
			(layers "F.Cu" "F.Mask" "F.Paste")
			(net "M_J_CPU0_SB_DQ<4>")
		)
		(pad "CF17" smd circle
			(at -19.889978 18.18005 180)
			(size 0.450088 0.450088)
			(layers "F.Cu" "F.Mask" "F.Paste")
			(net "GND")
		)
		(pad "CF18" smd circle
			(at -18.949924 18.18005 180)
			(size 0.450088 0.450088)
			(layers "F.Cu" "F.Mask" "F.Paste")
			(net "M_J_CPU0_SB_DQS_DP<5>")
		)
		(pad "CF19" smd circle
			(at -18.010124 18.18005 180)
			(size 0.450088 0.450088)
			(layers "F.Cu" "F.Mask" "F.Paste")
			(net "GND")
		)
		(pad "CF20" smd circle
			(at -17.07007 18.18005 180)
			(size 0.450088 0.450088)
			(layers "F.Cu" "F.Mask" "F.Paste")
			(net "M_I_CPU0_SB_DQ<4>")
		)
		(pad "CF21" smd circle
			(at -16.130016 18.18005 180)
			(size 0.450088 0.450088)
			(layers "F.Cu" "F.Mask" "F.Paste")
			(net "M_I_CPU0_SB_DQS_DP<5>")
		)
		(pad "CF22" smd circle
			(at -15.189962 18.18005 180)
			(size 0.450088 0.450088)
			(layers "F.Cu" "F.Mask" "F.Paste")
			(net "PVDD11_S3_P0")
		)
		(pad "CF23" smd circle
			(at -14.249908 18.18005 180)
			(size 0.450088 0.450088)
			(layers "F.Cu" "F.Mask" "F.Paste")
			(net "GND")
		)
		(pad "CF24" smd circle
			(at -13.310108 18.18005 180)
			(size 0.450088 0.450088)
			(layers "F.Cu" "F.Mask" "F.Paste")
			(net "GND")
		)
		(pad "CF25" smd circle
			(at -12.370054 18.18005 180)
			(size 0.450088 0.450088)
			(layers "F.Cu" "F.Mask" "F.Paste")
			(net "GND")
		)
		(pad "CF26" smd circle
			(at -11.43 18.18005 180)
			(size 0.450088 0.450088)
			(layers "F.Cu" "F.Mask" "F.Paste")
			(net "GND")
		)
		(pad "CF27" smd circle
			(at -10.489946 18.18005 180)
			(size 0.450088 0.450088)
			(layers "F.Cu" "F.Mask" "F.Paste")
			(net "GND")
		)
		(pad "CF28" smd circle
			(at -9.549892 18.18005 180)
			(size 0.450088 0.450088)
			(layers "F.Cu" "F.Mask" "F.Paste")
			(net "GND")
		)
		(pad "CF29" smd circle
			(at -8.610092 18.18005 180)
			(size 0.450088 0.450088)
			(layers "F.Cu" "F.Mask" "F.Paste")
			(net "GND")
		)
		(pad "CF30" smd circle
			(at -7.670038 18.18005 180)
			(size 0.450088 0.450088)
			(layers "F.Cu" "F.Mask" "F.Paste")
			(net "GND")
		)
		(pad "CF31" smd circle
			(at -6.729984 18.18005 180)
			(size 0.450088 0.450088)
			(layers "F.Cu" "F.Mask" "F.Paste")
			(net "GND")
		)
		(pad "CF32" smd circle
			(at -5.78993 18.18005 180)
			(size 0.450088 0.450088)
			(layers "F.Cu" "F.Mask" "F.Paste")
			(net "GND")
		)
		(pad "CF33" smd circle
			(at -4.849876 18.18005 180)
			(size 0.450088 0.450088)
			(layers "F.Cu" "F.Mask" "F.Paste")
			(net "GND")
		)
		(pad "CF34" smd circle
			(at -3.910076 18.18005 180)
			(size 0.450088 0.450088)
			(layers "F.Cu" "F.Mask" "F.Paste")
			(net "GND")
		)
		(pad "CF35" smd circle
			(at -2.970022 18.18005 180)
			(size 0.450088 0.450088)
			(layers "F.Cu" "F.Mask" "F.Paste")
			(net "P5E_CPU0_P3_TX_DN<1>")
		)
		(pad "CF36" smd circle
			(at -2.029968 18.18005 180)
			(size 0.450088 0.450088)
			(layers "F.Cu" "F.Mask" "F.Paste")
			(net "P5E_CPU0_P3_TX_DP<1>")
		)
		(pad "CF37" smd circle
			(at -1.089914 18.18005 180)
			(size 0.450088 0.450088)
			(layers "F.Cu" "F.Mask" "F.Paste")
			(net "GND")
		)
		(pad "CF39" smd circle
			(at 0.78994 18.18005 180)
			(size 0.450088 0.450088)
			(layers "F.Cu" "F.Mask" "F.Paste")
			(net "GND")
		)
		(pad "CF40" smd circle
			(at 1.729994 18.18005 180)
			(size 0.450088 0.450088)
			(layers "F.Cu" "F.Mask" "F.Paste")
			(net "P5E_CPU0_P1_RX_DP<14>")
		)
		(pad "CF41" smd circle
			(at 2.670048 18.18005 180)
			(size 0.450088 0.450088)
			(layers "F.Cu" "F.Mask" "F.Paste")
			(net "P5E_CPU0_P1_RX_DN<14>")
		)
		(pad "CF42" smd circle
			(at 3.610102 18.18005 180)
			(size 0.450088 0.450088)
			(layers "F.Cu" "F.Mask" "F.Paste")
			(net "GND")
		)
		(pad "CF43" smd circle
			(at 4.549902 18.18005 180)
			(size 0.450088 0.450088)
			(layers "F.Cu" "F.Mask" "F.Paste")
			(net "GND")
		)
		(pad "CF44" smd circle
			(at 5.489956 18.18005 180)
			(size 0.450088 0.450088)
			(layers "F.Cu" "F.Mask" "F.Paste")
			(net "GND")
		)
		(pad "CF45" smd circle
			(at 6.43001 18.18005 180)
			(size 0.450088 0.450088)
			(layers "F.Cu" "F.Mask" "F.Paste")
			(net "GND")
		)
		(pad "CF46" smd circle
			(at 7.370064 18.18005 180)
			(size 0.450088 0.450088)
			(layers "F.Cu" "F.Mask" "F.Paste")
			(net "GND")
		)
		(pad "CF47" smd circle
			(at 8.310118 18.18005 180)
			(size 0.450088 0.450088)
			(layers "F.Cu" "F.Mask" "F.Paste")
			(net "GND")
		)
		(pad "CF48" smd circle
			(at 9.249918 18.18005 180)
			(size 0.450088 0.450088)
			(layers "F.Cu" "F.Mask" "F.Paste")
			(net "GND")
		)
		(pad "CF49" smd circle
			(at 10.189972 18.18005 180)
			(size 0.450088 0.450088)
			(layers "F.Cu" "F.Mask" "F.Paste")
			(net "GND")
		)
		(pad "CF50" smd circle
			(at 11.130026 18.18005 180)
			(size 0.450088 0.450088)
			(layers "F.Cu" "F.Mask" "F.Paste")
			(net "GND")
		)
		(pad "CF51" smd circle
			(at 12.07008 18.18005 180)
			(size 0.450088 0.450088)
			(layers "F.Cu" "F.Mask" "F.Paste")
			(net "GND")
		)
		(pad "CF52" smd circle
			(at 13.00988 18.18005 180)
			(size 0.450088 0.450088)
			(layers "F.Cu" "F.Mask" "F.Paste")
			(net "GND")
		)
		(pad "CF53" smd circle
			(at 13.949934 18.18005 180)
			(size 0.450088 0.450088)
			(layers "F.Cu" "F.Mask" "F.Paste")
			(net "GND")
		)
		(pad "CF54" smd circle
			(at 14.889988 18.18005 180)
			(size 0.450088 0.450088)
			(layers "F.Cu" "F.Mask" "F.Paste")
			(net "PVDDIO_P0")
		)
		(pad "CF55" smd circle
			(at 15.830042 18.18005 180)
			(size 0.450088 0.450088)
			(layers "F.Cu" "F.Mask" "F.Paste")
			(net "M_C_CPU0_SB_DQS_DP<5>")
		)
		(pad "CF56" smd circle
			(at 16.770096 18.18005 180)
			(size 0.450088 0.450088)
			(layers "F.Cu" "F.Mask" "F.Paste")
			(net "M_C_CPU0_SB_DQ<4>")
		)
		(pad "CF57" smd circle
			(at 17.709896 18.18005 180)
			(size 0.450088 0.450088)
			(layers "F.Cu" "F.Mask" "F.Paste")
			(net "GND")
		)
		(pad "CF58" smd circle
			(at 18.64995 18.18005 180)
			(size 0.450088 0.450088)
			(layers "F.Cu" "F.Mask" "F.Paste")
			(net "M_D_CPU0_SB_DQS_DP<5>")
		)
	)
)
